# T6G (Grand Teton) — schematic netlist excerpt (pin names and nets, part order shuffled) for the footprints in the layout excerpt that follows; sources: Cadence DE-HDL packaged netlist, KiCad conversion of 04192023_DAF0TMB3IC0_F0TG_MB_C_brd_V02_OCP.brd

U223  74CBTLV3126PW  IC  pkg TSSOP14  page 138
  \1oe\  = FB_BMC_ISOLATE1
  \1a\  = NCSI_BMC_TXD1_R1
  \1b\  = NCSI_OCP_V3_2_TXD1
  \2oe\  = FB_BMC_ISOLATE1
  \2a\  = NCSI_BMC_TXD0_R1
  \2b\  = NCSI_OCP_V3_2_TXD0
  GND  = GND
  \3b\  = NCSI_OCP_V3_2_TX_EN
  \3a\  = NCSI_BMC_TX_EN_R1
  \3oe\  = FB_BMC_ISOLATE1
  \4b\  = OCP_V3_2_ISO2_RBT_ARB_OUT
  \4a\  = OCP_V3_2_RBT_ARB_OUT
  \4oe\  = FB_BMC_ISOLATE1
  VCC  = P3V3_AUX

C633  Q_CAP  100UF 4V 20% X6S  pkg C0805  page 290 : A = P0V9_CPU0_RT1_2A ; B = GND

(kicad_pcb
	(version 20260206)
	(generator "pcbnew")
	(generator_version "10.0")
	(general
		(thickness 1.6)
		(legacy_teardrops no)
	)
	(paper "A4")
	(title_block
		(title "04192023_DAF0TMB3IC0_F0TG_MB_C_brd_V02_OCP.brd")
		(comment 1 "Grand Teton / footprints 7856-7857 of 8354")
	)
	(layers
		(0 "F.Cu" signal "TOP")
		(4 "In1.Cu" signal "GND")
		(6 "In2.Cu" signal "IN1")
		(8 "In3.Cu" signal "GND1")
		(10 "In4.Cu" signal "IN2")
		(12 "In5.Cu" signal "GND2")
		(14 "In6.Cu" signal "IN3")
		(16 "In7.Cu" signal "GND3")
		(18 "In8.Cu" signal "VCC")
		(20 "In9.Cu" signal "VCC1")
		(22 "In10.Cu" signal "GND4")
		(24 "In11.Cu" signal "IN4")
		(26 "In12.Cu" signal "GND5")
		(28 "In13.Cu" signal "IN5")
		(30 "In14.Cu" signal "GND6")
		(32 "In15.Cu" signal "IN6")
		(34 "In16.Cu" signal "GND7")
		(2 "B.Cu" signal "BOTTOM")
		(9 "F.Adhes" user "F.Adhesive")
		(11 "B.Adhes" user "B.Adhesive")
		(13 "F.Paste" user "Package Geometry/Pastemask Top")
		(15 "B.Paste" user "Package Geometry/Pastemask Bottom")
		(5 "F.SilkS" user "Ref Des/Silkscreen Top")
		(7 "B.SilkS" user "Ref Des/Silkscreen Bottom")
		(1 "F.Mask" user "Board Geometry/Soldermask Top")
		(3 "B.Mask" user "Board Geometry/Soldermask Bottom")
		(17 "Dwgs.User" user "User.Drawings")
		(19 "Cmts.User" user "User.Comments")
		(21 "Eco1.User" user "User.Eco1")
		(23 "Eco2.User" user "User.Eco2")
		(25 "Edge.Cuts" user "Board Geometry/Outline")
		(27 "Margin" user)
		(31 "F.CrtYd" user "Package Geometry/Place Bound Top")
		(29 "B.CrtYd" user "Package Geometry/Place Bound Bottom")
		(35 "F.Fab" user "Ref Des/Assembly Top")
		(33 "B.Fab" user "Ref Des/Assembly Bottom")
	)
	(footprint ""
		(layer "B.Cu")
		(at 198.47433 -70.903084)
		(property "Reference" "U223"
			(at 1.73482 3.30073 0)
			(unlocked yes)
			(layer "B.SilkS")
			(effects
				(font
					(size 0.7874 0.5842)
					(thickness 0.1524)
				)
				(justify left mirror)
			)
		)
		(property "Value" ""
			(at 0 0 0)
			(layer "B.Fab")
			(effects
				(font
					(size 1.27 1.27)
				)
				(justify mirror)
			)
		)
		(duplicate_pad_numbers_are_jumpers no)
		(fp_line
			(start -2.0066 -2.5527)
			(end -2.0066 2.5527)
			(stroke
				(width 0.1524)
				(type default)
			)
			(layer "B.SilkS")
		)
		(fp_line
			(start -2.0066 2.5527)
			(end 2.0066 2.5527)
			(stroke
				(width 0.1524)
				(type default)
			)
			(layer "B.SilkS")
		)
		(fp_line
			(start -0.5715 -2.5527)
			(end -2.0066 -2.5527)
			(stroke
				(width 0.1524)
				(type default)
			)
			(layer "B.SilkS")
		)
		(fp_line
			(start 0 -1.9812)
			(end -0.5715 -2.5527)
			(stroke
				(width 0.1524)
				(type default)
			)
			(layer "B.SilkS")
		)
		(fp_line
			(start 0.5715 -2.5527)
			(end 0 -1.9812)
			(stroke
				(width 0.1524)
				(type default)
			)
			(layer "B.SilkS")
		)
		(fp_line
			(start 2.0066 -2.5527)
			(end 0.5715 -2.5527)
			(stroke
				(width 0.1524)
				(type default)
			)
			(layer "B.SilkS")
		)
		(fp_line
			(start 2.0066 2.5527)
			(end 2.0066 -2.5527)
			(stroke
				(width 0.1524)
				(type default)
			)
			(layer "B.SilkS")
		)
		(fp_poly
			(pts
				(xy 3.81 -1.905) (xy 4.36372 -2.233168) (xy 4.36372 -1.608328)
			)
			(stroke
				(width 0)
				(type default)
			)
			(fill yes)
			(layer "B.SilkS")
		)
		(fp_line
			(start -2.249932 -2.549906)
			(end -2.249932 2.549906)
			(stroke
				(width 0.1)
				(type default)
			)
			(layer "B.Fab")
		)
		(fp_line
			(start -2.249932 2.549906)
			(end 2.249932 2.549906)
			(stroke
				(width 0.1)
				(type default)
			)
			(layer "B.Fab")
		)
		(fp_line
			(start 2.249932 -2.549906)
			(end -2.249932 -2.549906)
			(stroke
				(width 0.1)
				(type default)
			)
			(layer "B.Fab")
		)
		(fp_line
			(start 2.249932 2.549906)
			(end 2.249932 -2.549906)
			(stroke
				(width 0.1)
				(type default)
			)
			(layer "B.Fab")
		)
		(fp_poly
			(pts
				(xy 4.36372 -1.608328) (xy 4.36372 -2.233168) (xy 3.81 -1.905)
			)
			(stroke
				(width 0)
				(type default)
			)
			(fill yes)
			(layer "B.Fab")
		)
		(pad "1" smd rect
			(at 2.921 -1.949958 270)
			(size 0.3556 1.4986)
			(layers "B.Cu" "B.Mask" "B.Paste")
			(net "FB_BMC_ISOLATE1")
		)
		(pad "2" smd rect
			(at 2.921 -1.299972 270)
			(size 0.3556 1.4986)
			(layers "B.Cu" "B.Mask" "B.Paste")
			(net "NCSI_BMC_TXD1_R1")
		)
		(pad "3" smd rect
			(at 2.921 -0.649986 270)
			(size 0.3556 1.4986)
			(layers "B.Cu" "B.Mask" "B.Paste")
			(net "NCSI_OCP_V3_2_TXD1")
		)
		(pad "4" smd rect
			(at 2.921 0 270)
			(size 0.3556 1.4986)
			(layers "B.Cu" "B.Mask" "B.Paste")
			(net "FB_BMC_ISOLATE1")
		)
		(pad "5" smd rect
			(at 2.921 0.649986 270)
			(size 0.3556 1.4986)
			(layers "B.Cu" "B.Mask" "B.Paste")
			(net "NCSI_BMC_TXD0_R1")
		)
		(pad "6" smd rect
			(at 2.921 1.299972 270)
			(size 0.3556 1.4986)
			(layers "B.Cu" "B.Mask" "B.Paste")
			(net "NCSI_OCP_V3_2_TXD0")
		)
		(pad "7" smd rect
			(at 2.921 1.949958 270)
			(size 0.3556 1.4986)
			(layers "B.Cu" "B.Mask" "B.Paste")
			(net "GND")
		)
		(pad "8" smd rect
			(at -2.921 1.949958 270)
			(size 0.3556 1.4986)
			(layers "B.Cu" "B.Mask" "B.Paste")
			(net "NCSI_OCP_V3_2_TX_EN")
		)
		(pad "9" smd rect
			(at -2.921 1.299972 270)
			(size 0.3556 1.4986)
			(layers "B.Cu" "B.Mask" "B.Paste")
			(net "NCSI_BMC_TX_EN_R1")
		)
		(pad "10" smd rect
			(at -2.921 0.649986 270)
			(size 0.3556 1.4986)
			(layers "B.Cu" "B.Mask" "B.Paste")
			(net "FB_BMC_ISOLATE1")
		)
		(pad "11" smd rect
			(at -2.921 0 270)
			(size 0.3556 1.4986)
			(layers "B.Cu" "B.Mask" "B.Paste")
			(net "OCP_V3_2_ISO2_RBT_ARB_OUT")
		)
		(pad "12" smd rect
			(at -2.921 -0.649986 270)
			(size 0.3556 1.4986)
			(layers "B.Cu" "B.Mask" "B.Paste")
			(net "OCP_V3_2_RBT_ARB_OUT")
		)
		(pad "13" smd rect
			(at -2.921 -1.299972 270)
			(size 0.3556 1.4986)
			(layers "B.Cu" "B.Mask" "B.Paste")
			(net "FB_BMC_ISOLATE1")
		)
		(pad "14" smd rect
			(at -2.921 -1.949958 270)
			(size 0.3556 1.4986)
			(layers "B.Cu" "B.Mask" "B.Paste")
			(net "P3V3_AUX")
		)
	)
	(footprint ""
		(layer "B.Cu")
		(at 330.947014 -398.969484)
		(property "Reference" "C633"
			(at 0 0 0)
			(layer "B.SilkS")
			(hide yes)
			(effects
				(font
					(size 1.27 1.27)
				)
				(justify mirror)
			)
		)
		(property "Value" ""
			(at 0 0 0)
			(layer "B.Fab")
			(effects
				(font
					(size 1.27 1.27)
				)
				(justify mirror)
			)
		)
		(duplicate_pad_numbers_are_jumpers no)
		(fp_line
			(start -1.524 -0.762)
			(end -1.524 0.762)
			(stroke
				(width 0.1524)
				(type default)
			)
			(layer "B.SilkS")
		)
		(fp_line
			(start -1.524 0.762)
			(end 1.524 0.762)
			(stroke
				(width 0.1524)
				(type default)
			)
			(layer "B.SilkS")
		)
		(fp_line
			(start 1.524 -0.762)
			(end -1.524 -0.762)
			(stroke
				(width 0.1524)
				(type default)
			)
			(layer "B.SilkS")
		)
		(fp_line
			(start 1.524 0.762)
			(end 1.524 -0.762)
			(stroke
				(width 0.1524)
				(type default)
			)
			(layer "B.SilkS")
		)
		(fp_line
			(start -1.1049 -0.724916)
			(end 1.1049 -0.724916)
			(stroke
				(width 0.1)
				(type default)
			)
			(layer "B.Fab")
		)
		(fp_line
			(start -1.1049 0.724916)
			(end -1.1049 -0.724916)
			(stroke
				(width 0.1)
				(type default)
			)
			(layer "B.Fab")
		)
		(fp_line
			(start 1.1049 -0.724916)
			(end 1.1049 0.724916)
			(stroke
				(width 0.1)
				(type default)
			)
			(layer "B.Fab")
		)
		(fp_line
			(start 1.1049 0.724916)
			(end -1.1049 0.724916)
			(stroke
				(width 0.1)
				(type default)
			)
			(layer "B.Fab")
		)
		(pad "1" smd rect
			(at 0.889 0)
			(size 1.016 1.27)
			(layers "B.Cu" "B.Mask" "B.Paste")
			(net "P0V9_CPU0_RT1_2A")
		)
		(pad "2" smd rect
			(at -0.889 0)
			(size 1.016 1.27)
			(layers "B.Cu" "B.Mask" "B.Paste")
			(net "GND")
		)
	)
)
